# S9S_MB_2U (Grand Teton) — schematic netlist excerpt (pin names and nets, part order shuffled) for the footprints in the layout excerpt that follows; sources: Cadence DE-HDL packaged netlist, KiCad conversion of 03242023_DA0F0TMBIJ0_F0T_Motherboard_J_brd_V01_OCP.brd

R284  Q_RES  10K 1% CHIP  pkg 0402LF  page 119 : A = P3V3_AUX ; B = FM_CPU0_PKGID1
C739  Q_CAP_DIFFBUS  DIFF BUS_0.22UF 6.3V 20% X6S  pkg C0201  page 176 : \1\ = P5E_CPU1_PE0_TX_C_DP<1> ; \2\ = P5E_CPU1_PE0_TX_DP<1>
R3453  Q_RES  100K 1% EMPTY  pkg 0402LF  page 149 : A = P3V3_AUX ; B = GPU_FPGA_BOOT_EN_BUF_R

(kicad_pcb
	(version 20260206)
	(generator "pcbnew")
	(generator_version "10.0")
	(general
		(thickness 1.6)
		(legacy_teardrops no)
	)
	(paper "A4")
	(title_block
		(title "03242023_DA0F0TMBIJ0_F0T_Motherboard_J_brd_V01_OCP.brd")
		(comment 1 "Grand Teton / footprints 189-191 of 6105")
	)
	(layers
		(0 "F.Cu" signal "TOP")
		(4 "In1.Cu" signal "GND")
		(6 "In2.Cu" signal "IN1")
		(8 "In3.Cu" signal "GND1")
		(10 "In4.Cu" signal "IN2")
		(12 "In5.Cu" signal "GND2")
		(14 "In6.Cu" signal "IN3")
		(16 "In7.Cu" signal "GND3")
		(18 "In8.Cu" signal "VCC")
		(20 "In9.Cu" signal "VCC1")
		(22 "In10.Cu" signal "GND4")
		(24 "In11.Cu" signal "IN4")
		(26 "In12.Cu" signal "GND5")
		(28 "In13.Cu" signal "IN5")
		(30 "In14.Cu" signal "GND6")
		(32 "In15.Cu" signal "IN6")
		(34 "In16.Cu" signal "GND7")
		(2 "B.Cu" signal "BOTTOM")
		(9 "F.Adhes" user "F.Adhesive")
		(11 "B.Adhes" user "B.Adhesive")
		(13 "F.Paste" user "Package Geometry/Pastemask Top")
		(15 "B.Paste" user "Package Geometry/Pastemask Bottom")
		(5 "F.SilkS" user "Ref Des/Silkscreen Top")
		(7 "B.SilkS" user "Ref Des/Silkscreen Bottom")
		(1 "F.Mask" user "Board Geometry/Soldermask Top")
		(3 "B.Mask" user "Board Geometry/Soldermask Bottom")
		(17 "Dwgs.User" user "User.Drawings")
		(19 "Cmts.User" user "User.Comments")
		(21 "Eco1.User" user "User.Eco1")
		(23 "Eco2.User" user "User.Eco2")
		(25 "Edge.Cuts" user "Board Geometry/Outline")
		(27 "Margin" user)
		(31 "F.CrtYd" user "Package Geometry/Place Bound Top")
		(29 "B.CrtYd" user "Package Geometry/Place Bound Bottom")
		(35 "F.Fab" user "Ref Des/Assembly Top")
		(33 "B.Fab" user "Ref Des/Assembly Bottom")
	)
	(footprint ""
		(layer "F.Cu")
		(at 170.23588 -439.003948 180)
		(property "Reference" "R3453"
			(at 0 0 180)
			(layer "F.SilkS")
			(hide yes)
			(effects
				(font
					(size 1.27 1.27)
				)
			)
		)
		(property "Value" ""
			(at 0 0 180)
			(layer "F.Fab")
			(effects
				(font
					(size 1.27 1.27)
				)
			)
		)
		(duplicate_pad_numbers_are_jumpers no)
		(fp_line
			(start 0.7874 0.4064)
			(end -0.7874 0.4064)
			(stroke
				(width 0.1524)
				(type default)
			)
			(layer "F.SilkS")
		)
		(fp_line
			(start 0.7874 -0.4064)
			(end 0.7874 0.4064)
			(stroke
				(width 0.1524)
				(type default)
			)
			(layer "F.SilkS")
		)
		(fp_line
			(start -0.7874 0.4064)
			(end -0.7874 -0.4064)
			(stroke
				(width 0.1524)
				(type default)
			)
			(layer "F.SilkS")
		)
		(fp_line
			(start -0.7874 -0.4064)
			(end 0.7874 -0.4064)
			(stroke
				(width 0.1524)
				(type default)
			)
			(layer "F.SilkS")
		)
		(fp_line
			(start 0.67945 0.3048)
			(end 0.120396 0.3048)
			(stroke
				(width 0.1)
				(type default)
			)
			(layer "F.Fab")
		)
		(fp_line
			(start 0.67945 -0.3048)
			(end 0.67945 0.3048)
			(stroke
				(width 0.1)
				(type default)
			)
			(layer "F.Fab")
		)
		(fp_line
			(start 0.12065 -0.2794)
			(end 0.12065 -0.3048)
			(stroke
				(width 0.1)
				(type default)
			)
			(layer "F.Fab")
		)
		(fp_line
			(start 0.12065 -0.3048)
			(end 0.67945 -0.3048)
			(stroke
				(width 0.1)
				(type default)
			)
			(layer "F.Fab")
		)
		(fp_line
			(start 0.120396 0.3048)
			(end 0.120396 0.2794)
			(stroke
				(width 0.1)
				(type default)
			)
			(layer "F.Fab")
		)
		(fp_line
			(start 0.120396 0.2794)
			(end -0.12065 0.2794)
			(stroke
				(width 0.1)
				(type default)
			)
			(layer "F.Fab")
		)
		(fp_line
			(start -0.12065 0.3048)
			(end -0.67945 0.3048)
			(stroke
				(width 0.1)
				(type default)
			)
			(layer "F.Fab")
		)
		(fp_line
			(start -0.12065 0.2794)
			(end -0.12065 0.3048)
			(stroke
				(width 0.1)
				(type default)
			)
			(layer "F.Fab")
		)
		(fp_line
			(start -0.12065 -0.2794)
			(end 0.12065 -0.2794)
			(stroke
				(width 0.1)
				(type default)
			)
			(layer "F.Fab")
		)
		(fp_line
			(start -0.12065 -0.305054)
			(end -0.12065 -0.2794)
			(stroke
				(width 0.1)
				(type default)
			)
			(layer "F.Fab")
		)
		(fp_line
			(start -0.67945 0.3048)
			(end -0.67945 -0.305054)
			(stroke
				(width 0.1)
				(type default)
			)
			(layer "F.Fab")
		)
		(fp_line
			(start -0.67945 -0.305054)
			(end -0.12065 -0.305054)
			(stroke
				(width 0.1)
				(type default)
			)
			(layer "F.Fab")
		)
		(pad "1" smd circle
			(at -0.40005 0 180)
			(size 0 0)
			(layers "F.Cu" "F.Mask" "F.Paste")
			(net "P3V3_AUX")
		)
		(pad "2" smd circle
			(at 0.40005 0 180)
			(size 0 0)
			(layers "F.Cu" "F.Mask" "F.Paste")
			(net "GPU_FPGA_BOOT_EN_BUF_R")
		)
	)
	(footprint ""
		(layer "F.Cu")
		(at 182.17388 -130.266948 -90)
		(property "Reference" "R284"
			(at 0 0 270)
			(layer "F.SilkS")
			(hide yes)
			(effects
				(font
					(size 1.27 1.27)
				)
			)
		)
		(property "Value" ""
			(at 0 0 270)
			(layer "F.Fab")
			(effects
				(font
					(size 1.27 1.27)
				)
			)
		)
		(duplicate_pad_numbers_are_jumpers no)
		(fp_line
			(start -0.7874 0.4064)
			(end -0.7874 -0.4064)
			(stroke
				(width 0.1524)
				(type default)
			)
			(layer "F.SilkS")
		)
		(fp_line
			(start 0.7874 0.4064)
			(end -0.7874 0.4064)
			(stroke
				(width 0.1524)
				(type default)
			)
			(layer "F.SilkS")
		)
		(fp_line
			(start -0.7874 -0.4064)
			(end 0.7874 -0.4064)
			(stroke
				(width 0.1524)
				(type default)
			)
			(layer "F.SilkS")
		)
		(fp_line
			(start 0.7874 -0.4064)
			(end 0.7874 0.4064)
			(stroke
				(width 0.1524)
				(type default)
			)
			(layer "F.SilkS")
		)
		(fp_line
			(start -0.67945 0.3048)
			(end -0.67945 -0.305054)
			(stroke
				(width 0.1)
				(type default)
			)
			(layer "F.Fab")
		)
		(fp_line
			(start -0.12065 0.3048)
			(end -0.67945 0.3048)
			(stroke
				(width 0.1)
				(type default)
			)
			(layer "F.Fab")
		)
		(fp_line
			(start 0.120396 0.3048)
			(end 0.120396 0.2794)
			(stroke
				(width 0.1)
				(type default)
			)
			(layer "F.Fab")
		)
		(fp_line
			(start 0.67945 0.3048)
			(end 0.120396 0.3048)
			(stroke
				(width 0.1)
				(type default)
			)
			(layer "F.Fab")
		)
		(fp_line
			(start -0.12065 0.2794)
			(end -0.12065 0.3048)
			(stroke
				(width 0.1)
				(type default)
			)
			(layer "F.Fab")
		)
		(fp_line
			(start 0.120396 0.2794)
			(end -0.12065 0.2794)
			(stroke
				(width 0.1)
				(type default)
			)
			(layer "F.Fab")
		)
		(fp_line
			(start -0.12065 -0.2794)
			(end 0.12065 -0.2794)
			(stroke
				(width 0.1)
				(type default)
			)
			(layer "F.Fab")
		)
		(fp_line
			(start 0.12065 -0.2794)
			(end 0.12065 -0.3048)
			(stroke
				(width 0.1)
				(type default)
			)
			(layer "F.Fab")
		)
		(fp_line
			(start 0.12065 -0.3048)
			(end 0.67945 -0.3048)
			(stroke
				(width 0.1)
				(type default)
			)
			(layer "F.Fab")
		)
		(fp_line
			(start 0.67945 -0.3048)
			(end 0.67945 0.3048)
			(stroke
				(width 0.1)
				(type default)
			)
			(layer "F.Fab")
		)
		(fp_line
			(start -0.67945 -0.305054)
			(end -0.12065 -0.305054)
			(stroke
				(width 0.1)
				(type default)
			)
			(layer "F.Fab")
		)
		(fp_line
			(start -0.12065 -0.305054)
			(end -0.12065 -0.2794)
			(stroke
				(width 0.1)
				(type default)
			)
			(layer "F.Fab")
		)
		(pad "1" smd circle
			(at -0.40005 0 270)
			(size 0 0)
			(layers "F.Cu" "F.Mask" "F.Paste")
			(net "P3V3_AUX")
		)
		(pad "2" smd circle
			(at 0.40005 0 270)
			(size 0 0)
			(layers "F.Cu" "F.Mask" "F.Paste")
			(net "FM_CPU0_PKGID1")
		)
	)
	(footprint ""
		(layer "F.Cu")
		(at 91.754198 -402.371052 -90)
		(property "Reference" "C739"
			(at 0 0 270)
			(layer "F.SilkS")
			(hide yes)
			(effects
				(font
					(size 1.27 1.27)
				)
			)
		)
		(property "Value" ""
			(at 0 0 270)
			(layer "F.Fab")
			(effects
				(font
					(size 1.27 1.27)
				)
			)
		)
		(duplicate_pad_numbers_are_jumpers no)
		(fp_line
			(start -0.299974 0.150114)
			(end -0.299974 -0.150114)
			(stroke
				(width 0.1)
				(type default)
			)
			(layer "F.Fab")
		)
		(fp_line
			(start 0.299974 0.150114)
			(end -0.299974 0.150114)
			(stroke
				(width 0.1)
				(type default)
			)
			(layer "F.Fab")
		)
		(fp_line
			(start -0.299974 -0.150114)
			(end 0.299974 -0.150114)
			(stroke
				(width 0.1)
				(type default)
			)
			(layer "F.Fab")
		)
		(fp_line
			(start 0.299974 -0.150114)
			(end 0.299974 0.150114)
			(stroke
				(width 0.1)
				(type default)
			)
			(layer "F.Fab")
		)
		(pad "1" smd rect
			(at -0.2667 0 270)
			(size 0.3048 0.381)
			(layers "F.Cu" "F.Mask" "F.Paste")
			(net "P5E_CPU1_PE0_TX_C_DP<1>")
		)
		(pad "2" smd rect
			(at 0.2667 0 270)
			(size 0.3048 0.381)
			(layers "F.Cu" "F.Mask" "F.Paste")
			(net "P5E_CPU1_PE0_TX_DP<1>")
		)
	)
)
